(kicad_pcb
	(version 20260206)
	(generator "pcbnew")
	(generator_version "10.0")
	(general
		(thickness 1.6)
		(legacy_teardrops no)
	)
	(paper "A4")
	(title_block
		(title "04192023_DAF0TMB3IC0_F0TG_MB_C_brd_V02_OCP.brd")
		(comment 1 "Grand Teton / footprints 3176-3182 of 8354")
	)
	(layers
		(0 "F.Cu" signal "TOP")
		(4 "In1.Cu" signal "GND")
		(6 "In2.Cu" signal "IN1")
		(8 "In3.Cu" signal "GND1")
		(10 "In4.Cu" signal "IN2")
		(12 "In5.Cu" signal "GND2")
		(14 "In6.Cu" signal "IN3")
		(16 "In7.Cu" signal "GND3")
		(18 "In8.Cu" signal "VCC")
		(20 "In9.Cu" signal "VCC1")
		(22 "In10.Cu" signal "GND4")
		(24 "In11.Cu" signal "IN4")
		(26 "In12.Cu" signal "GND5")
		(28 "In13.Cu" signal "IN5")
		(30 "In14.Cu" signal "GND6")
		(32 "In15.Cu" signal "IN6")
		(34 "In16.Cu" signal "GND7")
		(2 "B.Cu" signal "BOTTOM")
		(9 "F.Adhes" user "F.Adhesive")
		(11 "B.Adhes" user "B.Adhesive")
		(13 "F.Paste" user "Package Geometry/Pastemask Top")
		(15 "B.Paste" user "Package Geometry/Pastemask Bottom")
		(5 "F.SilkS" user "Ref Des/Silkscreen Top")
		(7 "B.SilkS" user "Ref Des/Silkscreen Bottom")
		(1 "F.Mask" user "Board Geometry/Soldermask Top")
		(3 "B.Mask" user "Board Geometry/Soldermask Bottom")
		(17 "Dwgs.User" user "User.Drawings")
		(19 "Cmts.User" user "User.Comments")
		(21 "Eco1.User" user "User.Eco1")
		(23 "Eco2.User" user "User.Eco2")
		(25 "Edge.Cuts" user "Board Geometry/Outline")
		(27 "Margin" user)
		(31 "F.CrtYd" user "Package Geometry/Place Bound Top")
		(29 "B.CrtYd" user "Package Geometry/Place Bound Bottom")
		(35 "F.Fab" user "Ref Des/Assembly Top")
		(33 "B.Fab" user "Ref Des/Assembly Bottom")
	)
	(footprint ""
		(layer "F.Cu")
		(at 449.044314 -25.10028 -90)
		(property "Reference" "PC2079"
			(at 0 0 270)
			(layer "F.SilkS")
			(hide yes)
			(effects
				(font
					(size 1.27 1.27)
				)
			)
		)
		(property "Value" ""
			(at 0 0 270)
			(layer "F.Fab")
			(effects
				(font
					(size 1.27 1.27)
				)
			)
		)
		(duplicate_pad_numbers_are_jumpers no)
		(fp_line
			(start -0.7874 0.4064)
			(end -0.7874 -0.4064)
			(stroke
				(width 0.1524)
				(type default)
			)
			(layer "F.SilkS")
		)
		(fp_line
			(start 0.7874 0.4064)
			(end -0.7874 0.4064)
			(stroke
				(width 0.1524)
				(type default)
			)
			(layer "F.SilkS")
		)
		(fp_line
			(start -0.7874 -0.4064)
			(end 0.7874 -0.4064)
			(stroke
				(width 0.1524)
				(type default)
			)
			(layer "F.SilkS")
		)
		(fp_line
			(start 0.7874 -0.4064)
			(end 0.7874 0.4064)
			(stroke
				(width 0.1524)
				(type default)
			)
			(layer "F.SilkS")
		)
		(fp_line
			(start -0.67945 0.3048)
			(end -0.67945 -0.305054)
			(stroke
				(width 0.1)
				(type default)
			)
			(layer "F.Fab")
		)
		(fp_line
			(start -0.12065 0.3048)
			(end -0.67945 0.3048)
			(stroke
				(width 0.1)
				(type default)
			)
			(layer "F.Fab")
		)
		(fp_line
			(start 0.120396 0.3048)
			(end 0.120396 0.2794)
			(stroke
				(width 0.1)
				(type default)
			)
			(layer "F.Fab")
		)
		(fp_line
			(start 0.67945 0.3048)
			(end 0.120396 0.3048)
			(stroke
				(width 0.1)
				(type default)
			)
			(layer "F.Fab")
		)
		(fp_line
			(start -0.12065 0.2794)
			(end -0.12065 0.3048)
			(stroke
				(width 0.1)
				(type default)
			)
			(layer "F.Fab")
		)
		(fp_line
			(start 0.120396 0.2794)
			(end -0.12065 0.2794)
			(stroke
				(width 0.1)
				(type default)
			)
			(layer "F.Fab")
		)
		(fp_line
			(start -0.12065 -0.2794)
			(end 0.12065 -0.2794)
			(stroke
				(width 0.1)
				(type default)
			)
			(layer "F.Fab")
		)
		(fp_line
			(start 0.12065 -0.2794)
			(end 0.12065 -0.3048)
			(stroke
				(width 0.1)
				(type default)
			)
			(layer "F.Fab")
		)
		(fp_line
			(start 0.12065 -0.3048)
			(end 0.67945 -0.3048)
			(stroke
				(width 0.1)
				(type default)
			)
			(layer "F.Fab")
		)
		(fp_line
			(start 0.67945 -0.3048)
			(end 0.67945 0.3048)
			(stroke
				(width 0.1)
				(type default)
			)
			(layer "F.Fab")
		)
		(fp_line
			(start -0.67945 -0.305054)
			(end -0.12065 -0.305054)
			(stroke
				(width 0.1)
				(type default)
			)
			(layer "F.Fab")
		)
		(fp_line
			(start -0.12065 -0.305054)
			(end -0.12065 -0.2794)
			(stroke
				(width 0.1)
				(type default)
			)
			(layer "F.Fab")
		)
		(pad "1" smd circle
			(at -0.40005 0 270)
			(size 0 0)
			(layers "F.Cu" "F.Mask" "F.Paste")
			(net "P12V_AUX")
		)
		(pad "2" smd circle
			(at 0.40005 0 270)
			(size 0 0)
			(layers "F.Cu" "F.Mask" "F.Paste")
			(net "GND")
		)
	)
	(footprint ""
		(layer "F.Cu")
		(at 102.751128 -184.427368 -90)
		(property "Reference" "PR522"
			(at 0 0 270)
			(layer "F.SilkS")
			(hide yes)
			(effects
				(font
					(size 1.27 1.27)
				)
			)
		)
		(property "Value" ""
			(at 0 0 270)
			(layer "F.Fab")
			(effects
				(font
					(size 1.27 1.27)
				)
			)
		)
		(duplicate_pad_numbers_are_jumpers no)
		(fp_line
			(start -0.7874 0.4064)
			(end -0.7874 -0.4064)
			(stroke
				(width 0.1524)
				(type default)
			)
			(layer "F.SilkS")
		)
		(fp_line
			(start 0.7874 0.4064)
			(end -0.7874 0.4064)
			(stroke
				(width 0.1524)
				(type default)
			)
			(layer "F.SilkS")
		)
		(fp_line
			(start -0.7874 -0.4064)
			(end 0.7874 -0.4064)
			(stroke
				(width 0.1524)
				(type default)
			)
			(layer "F.SilkS")
		)
		(fp_line
			(start 0.7874 -0.4064)
			(end 0.7874 0.4064)
			(stroke
				(width 0.1524)
				(type default)
			)
			(layer "F.SilkS")
		)
		(fp_line
			(start -0.67945 0.3048)
			(end -0.67945 -0.305054)
			(stroke
				(width 0.1)
				(type default)
			)
			(layer "F.Fab")
		)
		(fp_line
			(start -0.12065 0.3048)
			(end -0.67945 0.3048)
			(stroke
				(width 0.1)
				(type default)
			)
			(layer "F.Fab")
		)
		(fp_line
			(start 0.120396 0.3048)
			(end 0.120396 0.2794)
			(stroke
				(width 0.1)
				(type default)
			)
			(layer "F.Fab")
		)
		(fp_line
			(start 0.67945 0.3048)
			(end 0.120396 0.3048)
			(stroke
				(width 0.1)
				(type default)
			)
			(layer "F.Fab")
		)
		(fp_line
			(start -0.12065 0.2794)
			(end -0.12065 0.3048)
			(stroke
				(width 0.1)
				(type default)
			)
			(layer "F.Fab")
		)
		(fp_line
			(start 0.120396 0.2794)
			(end -0.12065 0.2794)
			(stroke
				(width 0.1)
				(type default)
			)
			(layer "F.Fab")
		)
		(fp_line
			(start -0.12065 -0.2794)
			(end 0.12065 -0.2794)
			(stroke
				(width 0.1)
				(type default)
			)
			(layer "F.Fab")
		)
		(fp_line
			(start 0.12065 -0.2794)
			(end 0.12065 -0.3048)
			(stroke
				(width 0.1)
				(type default)
			)
			(layer "F.Fab")
		)
		(fp_line
			(start 0.12065 -0.3048)
			(end 0.67945 -0.3048)
			(stroke
				(width 0.1)
				(type default)
			)
			(layer "F.Fab")
		)
		(fp_line
			(start 0.67945 -0.3048)
			(end 0.67945 0.3048)
			(stroke
				(width 0.1)
				(type default)
			)
			(layer "F.Fab")
		)
		(fp_line
			(start -0.67945 -0.305054)
			(end -0.12065 -0.305054)
			(stroke
				(width 0.1)
				(type default)
			)
			(layer "F.Fab")
		)
		(fp_line
			(start -0.12065 -0.305054)
			(end -0.12065 -0.2794)
			(stroke
				(width 0.1)
				(type default)
			)
			(layer "F.Fab")
		)
		(pad "1" smd circle
			(at -0.40005 0 270)
			(size 0 0)
			(layers "F.Cu" "F.Mask" "F.Paste")
			(net "SW_PVDDCR_CPU0_P1_SW3_RC")
		)
		(pad "2" smd circle
			(at 0.40005 0 270)
			(size 0 0)
			(layers "F.Cu" "F.Mask" "F.Paste")
			(net "GND")
		)
	)
	(footprint ""
		(layer "F.Cu")
		(at 217.1065 -402.191982 90)
		(property "Reference" "PC3272"
			(at 0 0 90)
			(layer "F.SilkS")
			(hide yes)
			(effects
				(font
					(size 1.27 1.27)
				)
			)
		)
		(property "Value" ""
			(at 0 0 90)
			(layer "F.Fab")
			(effects
				(font
					(size 1.27 1.27)
				)
			)
		)
		(duplicate_pad_numbers_are_jumpers no)
		(fp_line
			(start 0.7874 -0.4064)
			(end 0.7874 0.4064)
			(stroke
				(width 0.1524)
				(type default)
			)
			(layer "F.SilkS")
		)
		(fp_line
			(start -0.7874 -0.4064)
			(end 0.7874 -0.4064)
			(stroke
				(width 0.1524)
				(type default)
			)
			(layer "F.SilkS")
		)
		(fp_line
			(start 0.7874 0.4064)
			(end -0.7874 0.4064)
			(stroke
				(width 0.1524)
				(type default)
			)
			(layer "F.SilkS")
		)
		(fp_line
			(start -0.7874 0.4064)
			(end -0.7874 -0.4064)
			(stroke
				(width 0.1524)
				(type default)
			)
			(layer "F.SilkS")
		)
		(fp_line
			(start -0.12065 -0.305054)
			(end -0.12065 -0.2794)
			(stroke
				(width 0.1)
				(type default)
			)
			(layer "F.Fab")
		)
		(fp_line
			(start -0.67945 -0.305054)
			(end -0.12065 -0.305054)
			(stroke
				(width 0.1)
				(type default)
			)
			(layer "F.Fab")
		)
		(fp_line
			(start 0.67945 -0.3048)
			(end 0.67945 0.3048)
			(stroke
				(width 0.1)
				(type default)
			)
			(layer "F.Fab")
		)
		(fp_line
			(start 0.12065 -0.3048)
			(end 0.67945 -0.3048)
			(stroke
				(width 0.1)
				(type default)
			)
			(layer "F.Fab")
		)
		(fp_line
			(start 0.12065 -0.2794)
			(end 0.12065 -0.3048)
			(stroke
				(width 0.1)
				(type default)
			)
			(layer "F.Fab")
		)
		(fp_line
			(start -0.12065 -0.2794)
			(end 0.12065 -0.2794)
			(stroke
				(width 0.1)
				(type default)
			)
			(layer "F.Fab")
		)
		(fp_line
			(start 0.120396 0.2794)
			(end -0.12065 0.2794)
			(stroke
				(width 0.1)
				(type default)
			)
			(layer "F.Fab")
		)
		(fp_line
			(start -0.12065 0.2794)
			(end -0.12065 0.3048)
			(stroke
				(width 0.1)
				(type default)
			)
			(layer "F.Fab")
		)
		(fp_line
			(start 0.67945 0.3048)
			(end 0.120396 0.3048)
			(stroke
				(width 0.1)
				(type default)
			)
			(layer "F.Fab")
		)
		(fp_line
			(start 0.120396 0.3048)
			(end 0.120396 0.2794)
			(stroke
				(width 0.1)
				(type default)
			)
			(layer "F.Fab")
		)
		(fp_line
			(start -0.12065 0.3048)
			(end -0.67945 0.3048)
			(stroke
				(width 0.1)
				(type default)
			)
			(layer "F.Fab")
		)
		(fp_line
			(start -0.67945 0.3048)
			(end -0.67945 -0.305054)
			(stroke
				(width 0.1)
				(type default)
			)
			(layer "F.Fab")
		)
		(pad "1" smd circle
			(at -0.40005 0 90)
			(size 0 0)
			(layers "F.Cu" "F.Mask" "F.Paste")
			(net "HSC_VDD_R_3")
		)
		(pad "2" smd circle
			(at 0.40005 0 90)
			(size 0 0)
			(layers "F.Cu" "F.Mask" "F.Paste")
			(net "AGND_HSC")
		)
	)
	(footprint ""
		(layer "F.Cu")
		(at 47.768764 -408.517344 -90)
		(property "Reference" "C6630"
			(at 0 0 270)
			(layer "F.SilkS")
			(hide yes)
			(effects
				(font
					(size 1.27 1.27)
				)
			)
		)
		(property "Value" ""
			(at 0 0 270)
			(layer "F.Fab")
			(effects
				(font
					(size 1.27 1.27)
				)
			)
		)
		(duplicate_pad_numbers_are_jumpers no)
		(fp_line
			(start -0.299974 0.150114)
			(end -0.299974 -0.150114)
			(stroke
				(width 0.1)
				(type default)
			)
			(layer "F.Fab")
		)
		(fp_line
			(start 0.299974 0.150114)
			(end -0.299974 0.150114)
			(stroke
				(width 0.1)
				(type default)
			)
			(layer "F.Fab")
		)
		(fp_line
			(start -0.299974 -0.150114)
			(end 0.299974 -0.150114)
			(stroke
				(width 0.1)
				(type default)
			)
			(layer "F.Fab")
		)
		(fp_line
			(start 0.299974 -0.150114)
			(end 0.299974 0.150114)
			(stroke
				(width 0.1)
				(type default)
			)
			(layer "F.Fab")
		)
		(pad "1" smd rect
			(at -0.2667 0 270)
			(size 0.3048 0.381)
			(layers "F.Cu" "F.Mask" "F.Paste")
			(net "P5E_CPU1_P0_TX_BUF_C_DN<0>")
		)
		(pad "2" smd rect
			(at 0.2667 0 270)
			(size 0.3048 0.381)
			(layers "F.Cu" "F.Mask" "F.Paste")
			(net "P5E_CPU1_P0_TX_BUF_DN<0>")
		)
	)
	(footprint ""
		(layer "F.Cu")
		(at 97.177352 -74.76998)
		(property "Reference" "PC1321"
			(at 0 0 0)
			(layer "F.SilkS")
			(hide yes)
			(effects
				(font
					(size 1.27 1.27)
				)
			)
		)
		(property "Value" ""
			(at 0 0 0)
			(layer "F.Fab")
			(effects
				(font
					(size 1.27 1.27)
				)
			)
		)
		(duplicate_pad_numbers_are_jumpers no)
		(fp_line
			(start -0.7874 -0.4064)
			(end 0.7874 -0.4064)
			(stroke
				(width 0.1524)
				(type default)
			)
			(layer "F.SilkS")
		)
		(fp_line
			(start -0.7874 0.4064)
			(end -0.7874 -0.4064)
			(stroke
				(width 0.1524)
				(type default)
			)
			(layer "F.SilkS")
		)
		(fp_line
			(start 0.7874 -0.4064)
			(end 0.7874 0.4064)
			(stroke
				(width 0.1524)
				(type default)
			)
			(layer "F.SilkS")
		)
		(fp_line
			(start 0.7874 0.4064)
			(end -0.7874 0.4064)
			(stroke
				(width 0.1524)
				(type default)
			)
			(layer "F.SilkS")
		)
		(fp_line
			(start -0.67945 -0.305054)
			(end -0.12065 -0.305054)
			(stroke
				(width 0.1)
				(type default)
			)
			(layer "F.Fab")
		)
		(fp_line
			(start -0.67945 0.3048)
			(end -0.67945 -0.305054)
			(stroke
				(width 0.1)
				(type default)
			)
			(layer "F.Fab")
		)
		(fp_line
			(start -0.12065 -0.305054)
			(end -0.12065 -0.2794)
			(stroke
				(width 0.1)
				(type default)
			)
			(layer "F.Fab")
		)
		(fp_line
			(start -0.12065 -0.2794)
			(end 0.12065 -0.2794)
			(stroke
				(width 0.1)
				(type default)
			)
			(layer "F.Fab")
		)
		(fp_line
			(start -0.12065 0.2794)
			(end -0.12065 0.3048)
			(stroke
				(width 0.1)
				(type default)
			)
			(layer "F.Fab")
		)
		(fp_line
			(start -0.12065 0.3048)
			(end -0.67945 0.3048)
			(stroke
				(width 0.1)
				(type default)
			)
			(layer "F.Fab")
		)
		(fp_line
			(start 0.120396 0.2794)
			(end -0.12065 0.2794)
			(stroke
				(width 0.1)
				(type default)
			)
			(layer "F.Fab")
		)
		(fp_line
			(start 0.120396 0.3048)
			(end 0.120396 0.2794)
			(stroke
				(width 0.1)
				(type default)
			)
			(layer "F.Fab")
		)
		(fp_line
			(start 0.12065 -0.3048)
			(end 0.67945 -0.3048)
			(stroke
				(width 0.1)
				(type default)
			)
			(layer "F.Fab")
		)
		(fp_line
			(start 0.12065 -0.2794)
			(end 0.12065 -0.3048)
			(stroke
				(width 0.1)
				(type default)
			)
			(layer "F.Fab")
		)
		(fp_line
			(start 0.67945 -0.3048)
			(end 0.67945 0.3048)
			(stroke
				(width 0.1)
				(type default)
			)
			(layer "F.Fab")
		)
		(fp_line
			(start 0.67945 0.3048)
			(end 0.120396 0.3048)
			(stroke
				(width 0.1)
				(type default)
			)
			(layer "F.Fab")
		)
		(pad "1" smd circle
			(at -0.40005 0)
			(size 0 0)
			(layers "F.Cu" "F.Mask" "F.Paste")
			(net "P3V3_OCP_DVDT_2")
		)
		(pad "2" smd circle
			(at 0.40005 0)
			(size 0 0)
			(layers "F.Cu" "F.Mask" "F.Paste")
			(net "GND")
		)
	)
	(footprint ""
		(layer "F.Cu")
		(at 170.979846 -382.30429)
		(property "Reference" "R892"
			(at 0 0 0)
			(layer "F.SilkS")
			(hide yes)
			(effects
				(font
					(size 1.27 1.27)
				)
			)
		)
		(property "Value" ""
			(at 0 0 0)
			(layer "F.Fab")
			(effects
				(font
					(size 1.27 1.27)
				)
			)
		)
		(duplicate_pad_numbers_are_jumpers no)
		(fp_line
			(start -0.32512 -0.175006)
			(end 0.32512 -0.175006)
			(stroke
				(width 0.1)
				(type default)
			)
			(layer "F.Fab")
		)
		(fp_line
			(start -0.32512 0.175006)
			(end -0.32512 -0.175006)
			(stroke
				(width 0.1)
				(type default)
			)
			(layer "F.Fab")
		)
		(fp_line
			(start 0.32512 -0.175006)
			(end 0.32512 0.175006)
			(stroke
				(width 0.1)
				(type default)
			)
			(layer "F.Fab")
		)
		(fp_line
			(start 0.32512 0.175006)
			(end -0.32512 0.175006)
			(stroke
				(width 0.1)
				(type default)
			)
			(layer "F.Fab")
		)
		(pad "1" smd rect
			(at -0.2667 0)
			(size 0.3048 0.381)
			(layers "F.Cu" "F.Mask" "F.Paste")
			(net "RT_CPU1_P2_ADDR1")
		)
		(pad "2" smd rect
			(at 0.2667 0 180)
			(size 0.3048 0.381)
			(layers "F.Cu" "F.Mask" "F.Paste")
			(net "GND")
		)
	)
	(footprint ""
		(layer "F.Cu")
		(at 420.950136 -355.972364 90)
		(property "Reference" "PC201_1"
			(at 0 0 90)
			(layer "F.SilkS")
			(hide yes)
			(effects
				(font
					(size 1.27 1.27)
				)
			)
		)
		(property "Value" ""
			(at 0 0 90)
			(layer "F.Fab")
			(effects
				(font
					(size 1.27 1.27)
				)
			)
		)
		(duplicate_pad_numbers_are_jumpers no)
		(fp_line
			(start 0.7874 -0.4064)
			(end 0.7874 0.4064)
			(stroke
				(width 0.1524)
				(type default)
			)
			(layer "F.SilkS")
		)
		(fp_line
			(start -0.7874 -0.4064)
			(end 0.7874 -0.4064)
			(stroke
				(width 0.1524)
				(type default)
			)
			(layer "F.SilkS")
		)
		(fp_line
			(start 0.7874 0.4064)
			(end -0.7874 0.4064)
			(stroke
				(width 0.1524)
				(type default)
			)
			(layer "F.SilkS")
		)
		(fp_line
			(start -0.7874 0.4064)
			(end -0.7874 -0.4064)
			(stroke
				(width 0.1524)
				(type default)
			)
			(layer "F.SilkS")
		)
		(fp_line
			(start -0.12065 -0.305054)
			(end -0.12065 -0.2794)
			(stroke
				(width 0.1)
				(type default)
			)
			(layer "F.Fab")
		)
		(fp_line
			(start -0.67945 -0.305054)
			(end -0.12065 -0.305054)
			(stroke
				(width 0.1)
				(type default)
			)
			(layer "F.Fab")
		)
		(fp_line
			(start 0.67945 -0.3048)
			(end 0.67945 0.3048)
			(stroke
				(width 0.1)
				(type default)
			)
			(layer "F.Fab")
		)
		(fp_line
			(start 0.12065 -0.3048)
			(end 0.67945 -0.3048)
			(stroke
				(width 0.1)
				(type default)
			)
			(layer "F.Fab")
		)
		(fp_line
			(start 0.12065 -0.2794)
			(end 0.12065 -0.3048)
			(stroke
				(width 0.1)
				(type default)
			)
			(layer "F.Fab")
		)
		(fp_line
			(start -0.12065 -0.2794)
			(end 0.12065 -0.2794)
			(stroke
				(width 0.1)
				(type default)
			)
			(layer "F.Fab")
		)
		(fp_line
			(start 0.120396 0.2794)
			(end -0.12065 0.2794)
			(stroke
				(width 0.1)
				(type default)
			)
			(layer "F.Fab")
		)
		(fp_line
			(start -0.12065 0.2794)
			(end -0.12065 0.3048)
			(stroke
				(width 0.1)
				(type default)
			)
			(layer "F.Fab")
		)
		(fp_line
			(start 0.67945 0.3048)
			(end 0.120396 0.3048)
			(stroke
				(width 0.1)
				(type default)
			)
			(layer "F.Fab")
		)
		(fp_line
			(start 0.120396 0.3048)
			(end 0.120396 0.2794)
			(stroke
				(width 0.1)
				(type default)
			)
			(layer "F.Fab")
		)
		(fp_line
			(start -0.12065 0.3048)
			(end -0.67945 0.3048)
			(stroke
				(width 0.1)
				(type default)
			)
			(layer "F.Fab")
		)
		(fp_line
			(start -0.67945 0.3048)
			(end -0.67945 -0.305054)
			(stroke
				(width 0.1)
				(type default)
			)
			(layer "F.Fab")
		)
		(pad "1" smd circle
			(at -0.40005 0 90)
			(size 0 0)
			(layers "F.Cu" "F.Mask" "F.Paste")
			(net "PVDD11_S3_P0_VCCS")
		)
		(pad "2" smd circle
			(at 0.40005 0 90)
			(size 0 0)
			(layers "F.Cu" "F.Mask" "F.Paste")
			(net "GND")
		)
	)
)
